(kicad_pcb
	(version 20260206)
	(generator "pcbnew")
	(generator_version "10.0")
	(general
		(thickness 1.6)
		(legacy_teardrops no)
	)
	(paper "A4")
	(title_block
		(title "04192023_DAF0TMB3IC0_F0TG_MB_C_brd_V02_OCP.brd")
		(comment 1 "Grand Teton / footprints 5238-5243 of 8354")
	)
	(layers
		(0 "F.Cu" signal "TOP")
		(4 "In1.Cu" signal "GND")
		(6 "In2.Cu" signal "IN1")
		(8 "In3.Cu" signal "GND1")
		(10 "In4.Cu" signal "IN2")
		(12 "In5.Cu" signal "GND2")
		(14 "In6.Cu" signal "IN3")
		(16 "In7.Cu" signal "GND3")
		(18 "In8.Cu" signal "VCC")
		(20 "In9.Cu" signal "VCC1")
		(22 "In10.Cu" signal "GND4")
		(24 "In11.Cu" signal "IN4")
		(26 "In12.Cu" signal "GND5")
		(28 "In13.Cu" signal "IN5")
		(30 "In14.Cu" signal "GND6")
		(32 "In15.Cu" signal "IN6")
		(34 "In16.Cu" signal "GND7")
		(2 "B.Cu" signal "BOTTOM")
		(9 "F.Adhes" user "F.Adhesive")
		(11 "B.Adhes" user "B.Adhesive")
		(13 "F.Paste" user "Package Geometry/Pastemask Top")
		(15 "B.Paste" user "Package Geometry/Pastemask Bottom")
		(5 "F.SilkS" user "Ref Des/Silkscreen Top")
		(7 "B.SilkS" user "Ref Des/Silkscreen Bottom")
		(1 "F.Mask" user "Board Geometry/Soldermask Top")
		(3 "B.Mask" user "Board Geometry/Soldermask Bottom")
		(17 "Dwgs.User" user "User.Drawings")
		(19 "Cmts.User" user "User.Comments")
		(21 "Eco1.User" user "User.Eco1")
		(23 "Eco2.User" user "User.Eco2")
		(25 "Edge.Cuts" user "Board Geometry/Outline")
		(27 "Margin" user)
		(31 "F.CrtYd" user "Package Geometry/Place Bound Top")
		(29 "B.CrtYd" user "Package Geometry/Place Bound Bottom")
		(35 "F.Fab" user "Ref Des/Assembly Top")
		(33 "B.Fab" user "Ref Des/Assembly Bottom")
	)
	(footprint ""
		(layer "B.Cu")
		(at 384.113278 -143.250158)
		(property "Reference" "R8301"
			(at 0 0 0)
			(layer "B.SilkS")
			(hide yes)
			(effects
				(font
					(size 1.27 1.27)
				)
				(justify mirror)
			)
		)
		(property "Value" ""
			(at 0 0 0)
			(layer "B.Fab")
			(effects
				(font
					(size 1.27 1.27)
				)
				(justify mirror)
			)
		)
		(duplicate_pad_numbers_are_jumpers no)
		(fp_line
			(start -0.7874 -0.4064)
			(end -0.7874 0.4064)
			(stroke
				(width 0.1524)
				(type default)
			)
			(layer "B.SilkS")
		)
		(fp_line
			(start -0.7874 0.4064)
			(end 0.7874 0.4064)
			(stroke
				(width 0.1524)
				(type default)
			)
			(layer "B.SilkS")
		)
		(fp_line
			(start 0.7874 -0.4064)
			(end -0.7874 -0.4064)
			(stroke
				(width 0.1524)
				(type default)
			)
			(layer "B.SilkS")
		)
		(fp_line
			(start 0.7874 0.4064)
			(end 0.7874 -0.4064)
			(stroke
				(width 0.1524)
				(type default)
			)
			(layer "B.SilkS")
		)
		(fp_line
			(start -0.67945 -0.3048)
			(end -0.67945 0.3048)
			(stroke
				(width 0.1)
				(type default)
			)
			(layer "B.Fab")
		)
		(fp_line
			(start -0.67945 0.3048)
			(end -0.120396 0.3048)
			(stroke
				(width 0.1)
				(type default)
			)
			(layer "B.Fab")
		)
		(fp_line
			(start -0.12065 -0.3048)
			(end -0.67945 -0.3048)
			(stroke
				(width 0.1)
				(type default)
			)
			(layer "B.Fab")
		)
		(fp_line
			(start -0.12065 -0.2794)
			(end -0.12065 -0.3048)
			(stroke
				(width 0.1)
				(type default)
			)
			(layer "B.Fab")
		)
		(fp_line
			(start -0.120396 0.2794)
			(end 0.12065 0.2794)
			(stroke
				(width 0.1)
				(type default)
			)
			(layer "B.Fab")
		)
		(fp_line
			(start -0.120396 0.3048)
			(end -0.120396 0.2794)
			(stroke
				(width 0.1)
				(type default)
			)
			(layer "B.Fab")
		)
		(fp_line
			(start 0.12065 -0.305054)
			(end 0.12065 -0.2794)
			(stroke
				(width 0.1)
				(type default)
			)
			(layer "B.Fab")
		)
		(fp_line
			(start 0.12065 -0.2794)
			(end -0.12065 -0.2794)
			(stroke
				(width 0.1)
				(type default)
			)
			(layer "B.Fab")
		)
		(fp_line
			(start 0.12065 0.2794)
			(end 0.12065 0.3048)
			(stroke
				(width 0.1)
				(type default)
			)
			(layer "B.Fab")
		)
		(fp_line
			(start 0.12065 0.3048)
			(end 0.67945 0.3048)
			(stroke
				(width 0.1)
				(type default)
			)
			(layer "B.Fab")
		)
		(fp_line
			(start 0.67945 -0.305054)
			(end 0.12065 -0.305054)
			(stroke
				(width 0.1)
				(type default)
			)
			(layer "B.Fab")
		)
		(fp_line
			(start 0.67945 0.3048)
			(end 0.67945 -0.305054)
			(stroke
				(width 0.1)
				(type default)
			)
			(layer "B.Fab")
		)
		(pad "1" smd circle
			(at 0.40005 0 180)
			(size 0 0)
			(layers "B.Cu" "B.Mask" "B.Paste")
			(net "PVDDCR_CPU0_P0_OCP_N")
		)
		(pad "2" smd circle
			(at -0.40005 0 180)
			(size 0 0)
			(layers "B.Cu" "B.Mask" "B.Paste")
			(net "PVDDCR_CPU0_P0_OCP_N_R")
		)
	)
	(footprint ""
		(layer "B.Cu")
		(at 339.846158 -309.214012 -90)
		(property "Reference" "R393"
			(at 0 0 90)
			(layer "B.SilkS")
			(hide yes)
			(effects
				(font
					(size 1.27 1.27)
				)
				(justify mirror)
			)
		)
		(property "Value" ""
			(at 0 0 90)
			(layer "B.Fab")
			(effects
				(font
					(size 1.27 1.27)
				)
				(justify mirror)
			)
		)
		(duplicate_pad_numbers_are_jumpers no)
		(fp_line
			(start -0.7874 0.4064)
			(end 0.7874 0.4064)
			(stroke
				(width 0.1524)
				(type default)
			)
			(layer "B.SilkS")
		)
		(fp_line
			(start 0.7874 0.4064)
			(end 0.7874 -0.4064)
			(stroke
				(width 0.1524)
				(type default)
			)
			(layer "B.SilkS")
		)
		(fp_line
			(start -0.7874 -0.4064)
			(end -0.7874 0.4064)
			(stroke
				(width 0.1524)
				(type default)
			)
			(layer "B.SilkS")
		)
		(fp_line
			(start 0.7874 -0.4064)
			(end -0.7874 -0.4064)
			(stroke
				(width 0.1524)
				(type default)
			)
			(layer "B.SilkS")
		)
		(fp_line
			(start -0.67945 0.3048)
			(end -0.120396 0.3048)
			(stroke
				(width 0.1)
				(type default)
			)
			(layer "B.Fab")
		)
		(fp_line
			(start -0.120396 0.3048)
			(end -0.120396 0.2794)
			(stroke
				(width 0.1)
				(type default)
			)
			(layer "B.Fab")
		)
		(fp_line
			(start 0.12065 0.3048)
			(end 0.67945 0.3048)
			(stroke
				(width 0.1)
				(type default)
			)
			(layer "B.Fab")
		)
		(fp_line
			(start 0.67945 0.3048)
			(end 0.67945 -0.305054)
			(stroke
				(width 0.1)
				(type default)
			)
			(layer "B.Fab")
		)
		(fp_line
			(start -0.120396 0.2794)
			(end 0.12065 0.2794)
			(stroke
				(width 0.1)
				(type default)
			)
			(layer "B.Fab")
		)
		(fp_line
			(start 0.12065 0.2794)
			(end 0.12065 0.3048)
			(stroke
				(width 0.1)
				(type default)
			)
			(layer "B.Fab")
		)
		(fp_line
			(start -0.12065 -0.2794)
			(end -0.12065 -0.3048)
			(stroke
				(width 0.1)
				(type default)
			)
			(layer "B.Fab")
		)
		(fp_line
			(start 0.12065 -0.2794)
			(end -0.12065 -0.2794)
			(stroke
				(width 0.1)
				(type default)
			)
			(layer "B.Fab")
		)
		(fp_line
			(start -0.67945 -0.3048)
			(end -0.67945 0.3048)
			(stroke
				(width 0.1)
				(type default)
			)
			(layer "B.Fab")
		)
		(fp_line
			(start -0.12065 -0.3048)
			(end -0.67945 -0.3048)
			(stroke
				(width 0.1)
				(type default)
			)
			(layer "B.Fab")
		)
		(fp_line
			(start 0.12065 -0.305054)
			(end 0.12065 -0.2794)
			(stroke
				(width 0.1)
				(type default)
			)
			(layer "B.Fab")
		)
		(fp_line
			(start 0.67945 -0.305054)
			(end 0.12065 -0.305054)
			(stroke
				(width 0.1)
				(type default)
			)
			(layer "B.Fab")
		)
		(pad "1" smd circle
			(at 0.40005 0 90)
			(size 0 0)
			(layers "B.Cu" "B.Mask" "B.Paste")
			(net "CPU0_SA0")
		)
		(pad "2" smd circle
			(at -0.40005 0 90)
			(size 0 0)
			(layers "B.Cu" "B.Mask" "B.Paste")
			(net "GND")
		)
	)
	(footprint ""
		(layer "B.Cu")
		(at 111.981996 -26.952448 90)
		(property "Reference" "C6094"
			(at 0 0 90)
			(layer "B.SilkS")
			(hide yes)
			(effects
				(font
					(size 1.27 1.27)
				)
				(justify mirror)
			)
		)
		(property "Value" ""
			(at 0 0 90)
			(layer "B.Fab")
			(effects
				(font
					(size 1.27 1.27)
				)
				(justify mirror)
			)
		)
		(duplicate_pad_numbers_are_jumpers no)
		(fp_line
			(start 0.7874 -0.4064)
			(end -0.7874 -0.4064)
			(stroke
				(width 0.1524)
				(type default)
			)
			(layer "B.SilkS")
		)
		(fp_line
			(start -0.7874 -0.4064)
			(end -0.7874 0.4064)
			(stroke
				(width 0.1524)
				(type default)
			)
			(layer "B.SilkS")
		)
		(fp_line
			(start 0.7874 0.4064)
			(end 0.7874 -0.4064)
			(stroke
				(width 0.1524)
				(type default)
			)
			(layer "B.SilkS")
		)
		(fp_line
			(start -0.7874 0.4064)
			(end 0.7874 0.4064)
			(stroke
				(width 0.1524)
				(type default)
			)
			(layer "B.SilkS")
		)
		(fp_line
			(start 0.67945 -0.305054)
			(end 0.12065 -0.305054)
			(stroke
				(width 0.1)
				(type default)
			)
			(layer "B.Fab")
		)
		(fp_line
			(start 0.12065 -0.305054)
			(end 0.12065 -0.2794)
			(stroke
				(width 0.1)
				(type default)
			)
			(layer "B.Fab")
		)
		(fp_line
			(start -0.12065 -0.3048)
			(end -0.67945 -0.3048)
			(stroke
				(width 0.1)
				(type default)
			)
			(layer "B.Fab")
		)
		(fp_line
			(start -0.67945 -0.3048)
			(end -0.67945 0.3048)
			(stroke
				(width 0.1)
				(type default)
			)
			(layer "B.Fab")
		)
		(fp_line
			(start 0.12065 -0.2794)
			(end -0.12065 -0.2794)
			(stroke
				(width 0.1)
				(type default)
			)
			(layer "B.Fab")
		)
		(fp_line
			(start -0.12065 -0.2794)
			(end -0.12065 -0.3048)
			(stroke
				(width 0.1)
				(type default)
			)
			(layer "B.Fab")
		)
		(fp_line
			(start 0.12065 0.2794)
			(end 0.12065 0.3048)
			(stroke
				(width 0.1)
				(type default)
			)
			(layer "B.Fab")
		)
		(fp_line
			(start -0.120396 0.2794)
			(end 0.12065 0.2794)
			(stroke
				(width 0.1)
				(type default)
			)
			(layer "B.Fab")
		)
		(fp_line
			(start 0.67945 0.3048)
			(end 0.67945 -0.305054)
			(stroke
				(width 0.1)
				(type default)
			)
			(layer "B.Fab")
		)
		(fp_line
			(start 0.12065 0.3048)
			(end 0.67945 0.3048)
			(stroke
				(width 0.1)
				(type default)
			)
			(layer "B.Fab")
		)
		(fp_line
			(start -0.120396 0.3048)
			(end -0.120396 0.2794)
			(stroke
				(width 0.1)
				(type default)
			)
			(layer "B.Fab")
		)
		(fp_line
			(start -0.67945 0.3048)
			(end -0.120396 0.3048)
			(stroke
				(width 0.1)
				(type default)
			)
			(layer "B.Fab")
		)
		(pad "1" smd circle
			(at 0.40005 0 270)
			(size 0 0)
			(layers "B.Cu" "B.Mask" "B.Paste")
			(net "P3V3_AUX_CPU0_USB2_AVDD33")
		)
		(pad "2" smd circle
			(at -0.40005 0 270)
			(size 0 0)
			(layers "B.Cu" "B.Mask" "B.Paste")
			(net "GND")
		)
	)
	(footprint ""
		(layer "B.Cu")
		(at 288.935668 -194.88531 180)
		(property "Reference" "R762"
			(at 0 0 0)
			(layer "B.SilkS")
			(hide yes)
			(effects
				(font
					(size 1.27 1.27)
				)
				(justify mirror)
			)
		)
		(property "Value" ""
			(at 0 0 0)
			(layer "B.Fab")
			(effects
				(font
					(size 1.27 1.27)
				)
				(justify mirror)
			)
		)
		(duplicate_pad_numbers_are_jumpers no)
		(fp_line
			(start 0.7874 0.4064)
			(end 0.7874 -0.4064)
			(stroke
				(width 0.1524)
				(type default)
			)
			(layer "B.SilkS")
		)
		(fp_line
			(start 0.7874 -0.4064)
			(end -0.7874 -0.4064)
			(stroke
				(width 0.1524)
				(type default)
			)
			(layer "B.SilkS")
		)
		(fp_line
			(start -0.7874 0.4064)
			(end 0.7874 0.4064)
			(stroke
				(width 0.1524)
				(type default)
			)
			(layer "B.SilkS")
		)
		(fp_line
			(start -0.7874 -0.4064)
			(end -0.7874 0.4064)
			(stroke
				(width 0.1524)
				(type default)
			)
			(layer "B.SilkS")
		)
		(fp_line
			(start 0.67945 0.3048)
			(end 0.67945 -0.305054)
			(stroke
				(width 0.1)
				(type default)
			)
			(layer "B.Fab")
		)
		(fp_line
			(start 0.67945 -0.305054)
			(end 0.12065 -0.305054)
			(stroke
				(width 0.1)
				(type default)
			)
			(layer "B.Fab")
		)
		(fp_line
			(start 0.12065 0.3048)
			(end 0.67945 0.3048)
			(stroke
				(width 0.1)
				(type default)
			)
			(layer "B.Fab")
		)
		(fp_line
			(start 0.12065 0.2794)
			(end 0.12065 0.3048)
			(stroke
				(width 0.1)
				(type default)
			)
			(layer "B.Fab")
		)
		(fp_line
			(start 0.12065 -0.2794)
			(end -0.12065 -0.2794)
			(stroke
				(width 0.1)
				(type default)
			)
			(layer "B.Fab")
		)
		(fp_line
			(start 0.12065 -0.305054)
			(end 0.12065 -0.2794)
			(stroke
				(width 0.1)
				(type default)
			)
			(layer "B.Fab")
		)
		(fp_line
			(start -0.120396 0.3048)
			(end -0.120396 0.2794)
			(stroke
				(width 0.1)
				(type default)
			)
			(layer "B.Fab")
		)
		(fp_line
			(start -0.120396 0.2794)
			(end 0.12065 0.2794)
			(stroke
				(width 0.1)
				(type default)
			)
			(layer "B.Fab")
		)
		(fp_line
			(start -0.12065 -0.2794)
			(end -0.12065 -0.3048)
			(stroke
				(width 0.1)
				(type default)
			)
			(layer "B.Fab")
		)
		(fp_line
			(start -0.12065 -0.3048)
			(end -0.67945 -0.3048)
			(stroke
				(width 0.1)
				(type default)
			)
			(layer "B.Fab")
		)
		(fp_line
			(start -0.67945 0.3048)
			(end -0.120396 0.3048)
			(stroke
				(width 0.1)
				(type default)
			)
			(layer "B.Fab")
		)
		(fp_line
			(start -0.67945 -0.3048)
			(end -0.67945 0.3048)
			(stroke
				(width 0.1)
				(type default)
			)
			(layer "B.Fab")
		)
		(pad "1" smd circle
			(at 0.40005 0)
			(size 0 0)
			(layers "B.Cu" "B.Mask" "B.Paste")
			(net "PD_CHC_CPU0_DIMM_SAA")
		)
		(pad "2" smd circle
			(at -0.40005 0)
			(size 0 0)
			(layers "B.Cu" "B.Mask" "B.Paste")
			(net "GND")
		)
	)
	(footprint ""
		(layer "B.Cu")
		(at 133.332474 -165.190932 90)
		(property "Reference" "PC342_2"
			(at 0 0 90)
			(layer "B.SilkS")
			(hide yes)
			(effects
				(font
					(size 1.27 1.27)
				)
				(justify mirror)
			)
		)
		(property "Value" ""
			(at 0 0 90)
			(layer "B.Fab")
			(effects
				(font
					(size 1.27 1.27)
				)
				(justify mirror)
			)
		)
		(duplicate_pad_numbers_are_jumpers no)
		(fp_line
			(start 1.524 -0.762)
			(end -1.524 -0.762)
			(stroke
				(width 0.1524)
				(type default)
			)
			(layer "B.SilkS")
		)
		(fp_line
			(start -1.524 -0.762)
			(end -1.524 0.762)
			(stroke
				(width 0.1524)
				(type default)
			)
			(layer "B.SilkS")
		)
		(fp_line
			(start 1.524 0.762)
			(end 1.524 -0.762)
			(stroke
				(width 0.1524)
				(type default)
			)
			(layer "B.SilkS")
		)
		(fp_line
			(start -1.524 0.762)
			(end 1.524 0.762)
			(stroke
				(width 0.1524)
				(type default)
			)
			(layer "B.SilkS")
		)
		(fp_line
			(start 1.1049 -0.724916)
			(end 1.1049 0.724916)
			(stroke
				(width 0.1)
				(type default)
			)
			(layer "B.Fab")
		)
		(fp_line
			(start -1.1049 -0.724916)
			(end 1.1049 -0.724916)
			(stroke
				(width 0.1)
				(type default)
			)
			(layer "B.Fab")
		)
		(fp_line
			(start 1.1049 0.724916)
			(end -1.1049 0.724916)
			(stroke
				(width 0.1)
				(type default)
			)
			(layer "B.Fab")
		)
		(fp_line
			(start -1.1049 0.724916)
			(end -1.1049 -0.724916)
			(stroke
				(width 0.1)
				(type default)
			)
			(layer "B.Fab")
		)
		(pad "1" smd rect
			(at 0.889 0 90)
			(size 1.016 1.27)
			(layers "B.Cu" "B.Mask" "B.Paste")
			(net "PVDDCR_SOC_P1")
		)
		(pad "2" smd rect
			(at -0.889 0 90)
			(size 1.016 1.27)
			(layers "B.Cu" "B.Mask" "B.Paste")
			(net "GND")
		)
	)
	(footprint ""
		(layer "B.Cu")
		(at 98.578924 -258.830318 180)
		(property "Reference" "C2109"
			(at 0 0 0)
			(layer "B.SilkS")
			(hide yes)
			(effects
				(font
					(size 1.27 1.27)
				)
				(justify mirror)
			)
		)
		(property "Value" ""
			(at 0 0 0)
			(layer "B.Fab")
			(effects
				(font
					(size 1.27 1.27)
				)
				(justify mirror)
			)
		)
		(duplicate_pad_numbers_are_jumpers no)
		(fp_line
			(start 0.7874 0.4064)
			(end 0.7874 -0.4064)
			(stroke
				(width 0.1524)
				(type default)
			)
			(layer "B.SilkS")
		)
		(fp_line
			(start 0.7874 -0.4064)
			(end -0.7874 -0.4064)
			(stroke
				(width 0.1524)
				(type default)
			)
			(layer "B.SilkS")
		)
		(fp_line
			(start -0.7874 0.4064)
			(end 0.7874 0.4064)
			(stroke
				(width 0.1524)
				(type default)
			)
			(layer "B.SilkS")
		)
		(fp_line
			(start -0.7874 -0.4064)
			(end -0.7874 0.4064)
			(stroke
				(width 0.1524)
				(type default)
			)
			(layer "B.SilkS")
		)
		(fp_line
			(start 0.67945 0.3048)
			(end 0.67945 -0.305054)
			(stroke
				(width 0.1)
				(type default)
			)
			(layer "B.Fab")
		)
		(fp_line
			(start 0.67945 -0.305054)
			(end 0.12065 -0.305054)
			(stroke
				(width 0.1)
				(type default)
			)
			(layer "B.Fab")
		)
		(fp_line
			(start 0.12065 0.3048)
			(end 0.67945 0.3048)
			(stroke
				(width 0.1)
				(type default)
			)
			(layer "B.Fab")
		)
		(fp_line
			(start 0.12065 0.2794)
			(end 0.12065 0.3048)
			(stroke
				(width 0.1)
				(type default)
			)
			(layer "B.Fab")
		)
		(fp_line
			(start 0.12065 -0.2794)
			(end -0.12065 -0.2794)
			(stroke
				(width 0.1)
				(type default)
			)
			(layer "B.Fab")
		)
		(fp_line
			(start 0.12065 -0.305054)
			(end 0.12065 -0.2794)
			(stroke
				(width 0.1)
				(type default)
			)
			(layer "B.Fab")
		)
		(fp_line
			(start -0.120396 0.3048)
			(end -0.120396 0.2794)
			(stroke
				(width 0.1)
				(type default)
			)
			(layer "B.Fab")
		)
		(fp_line
			(start -0.120396 0.2794)
			(end 0.12065 0.2794)
			(stroke
				(width 0.1)
				(type default)
			)
			(layer "B.Fab")
		)
		(fp_line
			(start -0.12065 -0.2794)
			(end -0.12065 -0.3048)
			(stroke
				(width 0.1)
				(type default)
			)
			(layer "B.Fab")
		)
		(fp_line
			(start -0.12065 -0.3048)
			(end -0.67945 -0.3048)
			(stroke
				(width 0.1)
				(type default)
			)
			(layer "B.Fab")
		)
		(fp_line
			(start -0.67945 0.3048)
			(end -0.120396 0.3048)
			(stroke
				(width 0.1)
				(type default)
			)
			(layer "B.Fab")
		)
		(fp_line
			(start -0.67945 -0.3048)
			(end -0.67945 0.3048)
			(stroke
				(width 0.1)
				(type default)
			)
			(layer "B.Fab")
		)
		(pad "1" smd circle
			(at 0.40005 0)
			(size 0 0)
			(layers "B.Cu" "B.Mask" "B.Paste")
			(net "PVDDIO_P1")
		)
		(pad "2" smd circle
			(at -0.40005 0)
			(size 0 0)
			(layers "B.Cu" "B.Mask" "B.Paste")
			(net "GND")
		)
	)
)
